FILE_TYPE = CONNECTIVITY;
{Allegro Design Entry HDL 17.2-2016 S081 (4005846) 1/11/2022}
"PAGE_NUMBER" = 62;
0"NC";
END.
